# SCM (Grand Teton) — schematic netlist excerpt (pin names and nets, part order shuffled) for the footprints in the layout excerpt that follows; sources: Cadence DE-HDL packaged netlist, KiCad conversion of 12092022_DA0F0TMDCD0_F0T_Management_Board_D_brd_V3_OCP.brd

D9  SCHOTTKY_AC  SS0530 EMPTY  pkg SOD123XD  page 23 : A = P5V_AUX ; C = CRT_VCC5
R790  Q_RES  2K 1% CHIP  pkg 0402LF  page 15 : A = P3V3_SENSOR ; B = GND

(kicad_pcb
	(version 20260206)
	(generator "pcbnew")
	(generator_version "10.0")
	(general
		(thickness 1.6)
		(legacy_teardrops no)
	)
	(paper "A4")
	(title_block
		(title "12092022_DA0F0TMDCD0_F0T_Management_Board_D_brd_V3_OCP.brd")
		(comment 1 "Grand Teton / footprints 1217-1218 of 1440")
	)
	(layers
		(0 "F.Cu" signal "TOP")
		(4 "In1.Cu" signal "GND")
		(6 "In2.Cu" signal "IN1")
		(8 "In3.Cu" signal "GND1")
		(10 "In4.Cu" signal "IN2")
		(12 "In5.Cu" signal "VCC")
		(14 "In6.Cu" signal "VCC1")
		(16 "In7.Cu" signal "IN3")
		(18 "In8.Cu" signal "GND2")
		(20 "In9.Cu" signal "IN4")
		(22 "In10.Cu" signal "GND3")
		(2 "B.Cu" signal "BOTTOM")
		(9 "F.Adhes" user "F.Adhesive")
		(11 "B.Adhes" user "B.Adhesive")
		(13 "F.Paste" user "Package Geometry/Pastemask Top")
		(15 "B.Paste" user "Package Geometry/Pastemask Bottom")
		(5 "F.SilkS" user "Ref Des/Silkscreen Top")
		(7 "B.SilkS" user "Ref Des/Silkscreen Bottom")
		(1 "F.Mask" user "Board Geometry/Soldermask Top")
		(3 "B.Mask" user "Board Geometry/Soldermask Bottom")
		(17 "Dwgs.User" user "User.Drawings")
		(19 "Cmts.User" user "User.Comments")
		(21 "Eco1.User" user "User.Eco1")
		(23 "Eco2.User" user "User.Eco2")
		(25 "Edge.Cuts" user "Board Geometry/Outline")
		(27 "Margin" user)
		(31 "F.CrtYd" user "Package Geometry/Place Bound Top")
		(29 "B.CrtYd" user "Package Geometry/Place Bound Bottom")
		(35 "F.Fab" user "Ref Des/Assembly Top")
		(33 "B.Fab" user "Ref Des/Assembly Bottom")
	)
	(footprint ""
		(layer "B.Cu")
		(at 51.255168 -69.397372 -90)
		(property "Reference" "R790"
			(at 0 0 90)
			(layer "B.SilkS")
			(hide yes)
			(effects
				(font
					(size 1.27 1.27)
				)
				(justify mirror)
			)
		)
		(property "Value" ""
			(at 0 0 90)
			(layer "B.Fab")
			(effects
				(font
					(size 1.27 1.27)
				)
				(justify mirror)
			)
		)
		(duplicate_pad_numbers_are_jumpers no)
		(fp_line
			(start -0.7874 0.4064)
			(end 0.7874 0.4064)
			(stroke
				(width 0.1524)
				(type default)
			)
			(layer "B.SilkS")
		)
		(fp_line
			(start 0.7874 0.4064)
			(end 0.7874 -0.4064)
			(stroke
				(width 0.1524)
				(type default)
			)
			(layer "B.SilkS")
		)
		(fp_line
			(start -0.7874 -0.4064)
			(end -0.7874 0.4064)
			(stroke
				(width 0.1524)
				(type default)
			)
			(layer "B.SilkS")
		)
		(fp_line
			(start 0.7874 -0.4064)
			(end -0.7874 -0.4064)
			(stroke
				(width 0.1524)
				(type default)
			)
			(layer "B.SilkS")
		)
		(fp_line
			(start -0.67945 0.3048)
			(end -0.120396 0.3048)
			(stroke
				(width 0.1)
				(type default)
			)
			(layer "B.Fab")
		)
		(fp_line
			(start -0.120396 0.3048)
			(end -0.120396 0.2794)
			(stroke
				(width 0.1)
				(type default)
			)
			(layer "B.Fab")
		)
		(fp_line
			(start 0.12065 0.3048)
			(end 0.67945 0.3048)
			(stroke
				(width 0.1)
				(type default)
			)
			(layer "B.Fab")
		)
		(fp_line
			(start 0.67945 0.3048)
			(end 0.67945 -0.305054)
			(stroke
				(width 0.1)
				(type default)
			)
			(layer "B.Fab")
		)
		(fp_line
			(start -0.120396 0.2794)
			(end 0.12065 0.2794)
			(stroke
				(width 0.1)
				(type default)
			)
			(layer "B.Fab")
		)
		(fp_line
			(start 0.12065 0.2794)
			(end 0.12065 0.3048)
			(stroke
				(width 0.1)
				(type default)
			)
			(layer "B.Fab")
		)
		(fp_line
			(start -0.12065 -0.2794)
			(end -0.12065 -0.3048)
			(stroke
				(width 0.1)
				(type default)
			)
			(layer "B.Fab")
		)
		(fp_line
			(start 0.12065 -0.2794)
			(end -0.12065 -0.2794)
			(stroke
				(width 0.1)
				(type default)
			)
			(layer "B.Fab")
		)
		(fp_line
			(start -0.67945 -0.3048)
			(end -0.67945 0.3048)
			(stroke
				(width 0.1)
				(type default)
			)
			(layer "B.Fab")
		)
		(fp_line
			(start -0.12065 -0.3048)
			(end -0.67945 -0.3048)
			(stroke
				(width 0.1)
				(type default)
			)
			(layer "B.Fab")
		)
		(fp_line
			(start 0.12065 -0.305054)
			(end 0.12065 -0.2794)
			(stroke
				(width 0.1)
				(type default)
			)
			(layer "B.Fab")
		)
		(fp_line
			(start 0.67945 -0.305054)
			(end 0.12065 -0.305054)
			(stroke
				(width 0.1)
				(type default)
			)
			(layer "B.Fab")
		)
		(pad "1" smd circle
			(at 0.40005 0 90)
			(size 0 0)
			(layers "B.Cu" "B.Mask" "B.Paste")
			(net "P3V3_SENSOR")
		)
		(pad "2" smd circle
			(at -0.40005 0 90)
			(size 0 0)
			(layers "B.Cu" "B.Mask" "B.Paste")
			(net "GND")
		)
	)
	(footprint ""
		(layer "B.Cu")
		(at 28.702 -37.581078 90)
		(property "Reference" "D9"
			(at -3.799078 -2.71907 270)
			(unlocked yes)
			(layer "B.SilkS")
			(effects
				(font
					(size 0.7874 0.5842)
					(thickness 0.1524)
				)
				(justify left mirror)
			)
		)
		(property "Value" ""
			(at 0 0 90)
			(layer "B.Fab")
			(effects
				(font
					(size 1.27 1.27)
				)
				(justify mirror)
			)
		)
		(duplicate_pad_numbers_are_jumpers no)
		(fp_line
			(start 2.262378 -0.899922)
			(end 2.262378 0.899922)
			(stroke
				(width 0.1524)
				(type default)
			)
			(layer "B.SilkS")
		)
		(fp_line
			(start -2.567178 -0.899922)
			(end 2.262378 -0.899922)
			(stroke
				(width 0.1524)
				(type default)
			)
			(layer "B.SilkS")
		)
		(fp_line
			(start 0.3175 -0.508)
			(end 0.3175 0.508)
			(stroke
				(width 0.1524)
				(type default)
			)
			(layer "B.SilkS")
		)
		(fp_line
			(start -0.3175 -0.508)
			(end -0.3175 0.508)
			(stroke
				(width 0.1524)
				(type default)
			)
			(layer "B.SilkS")
		)
		(fp_line
			(start 0.8255 0)
			(end 0.3175 0)
			(stroke
				(width 0.1524)
				(type default)
			)
			(layer "B.SilkS")
		)
		(fp_line
			(start -0.3175 0)
			(end 0.3175 -0.508)
			(stroke
				(width 0.1524)
				(type default)
			)
			(layer "B.SilkS")
		)
		(fp_line
			(start -0.3175 0)
			(end -0.8255 0)
			(stroke
				(width 0.1524)
				(type default)
			)
			(layer "B.SilkS")
		)
		(fp_line
			(start 0.3175 0.508)
			(end -0.3175 0)
			(stroke
				(width 0.1524)
				(type default)
			)
			(layer "B.SilkS")
		)
		(fp_line
			(start 2.262378 0.899922)
			(end -2.567178 0.899922)
			(stroke
				(width 0.1524)
				(type default)
			)
			(layer "B.SilkS")
		)
		(fp_line
			(start -2.567178 0.899922)
			(end -2.567178 -0.899922)
			(stroke
				(width 0.1524)
				(type default)
			)
			(layer "B.SilkS")
		)
		(fp_poly
			(pts
				(xy -2.567178 -0.899922) (xy -2.186178 -0.899922) (xy -2.186178 0.899922) (xy -2.567178 0.899922)
			)
			(stroke
				(width 0)
				(type default)
			)
			(fill yes)
			(layer "B.SilkS")
		)
		(fp_line
			(start 1.400048 -0.899922)
			(end 1.400048 0.899922)
			(stroke
				(width 0.1)
				(type default)
			)
			(layer "B.Fab")
		)
		(fp_line
			(start -1.400048 -0.899922)
			(end 1.400048 -0.899922)
			(stroke
				(width 0.1)
				(type default)
			)
			(layer "B.Fab")
		)
		(fp_line
			(start 1.400048 0.899922)
			(end -1.400048 0.899922)
			(stroke
				(width 0.1)
				(type default)
			)
			(layer "B.Fab")
		)
		(fp_line
			(start -1.400048 0.899922)
			(end -1.400048 -0.899922)
			(stroke
				(width 0.1)
				(type default)
			)
			(layer "B.Fab")
		)
		(fp_text user "+"
			(at 3.19405 0.0254 0)
			(unlocked yes)
			(layer "B.SilkS")
			(effects
				(font
					(size 1.905 1.4224)
					(thickness 0.1524)
				)
				(justify left mirror)
			)
		)
		(fp_text user "-"
			(at -3.937762 0.241046 270)
			(unlocked yes)
			(layer "B.SilkS")
			(effects
				(font
					(size 1.905 1.4224)
					(thickness 0.1524)
				)
				(justify left mirror)
			)
		)
		(fp_text user "-"
			(at -3.937762 0.241046 270)
			(unlocked yes)
			(layer "B.Fab")
			(effects
				(font
					(size 1.905 1.4224)
					(thickness 0.1524)
				)
				(justify left mirror)
			)
		)
		(fp_text user "+"
			(at 3.29565 0.6858 0)
			(unlocked yes)
			(layer "B.Fab")
			(effects
				(font
					(size 1.905 1.4224)
					(thickness 0.1524)
				)
				(justify left mirror)
			)
		)
		(pad "A" smd rect
			(at 1.640078 0 270)
			(size 0.9906 1.2192)
			(layers "B.Cu" "B.Mask" "B.Paste")
			(net "P5V_AUX")
		)
		(pad "C" smd rect
			(at -1.640078 0 270)
			(size 0.9906 1.2192)
			(layers "B.Cu" "B.Mask" "B.Paste")
			(net "CRT_VCC5")
		)
	)
)
